# TIMECARD (Time Appliance Project (Time Card)) — schematic parts with pin connectivity, parts 731–876 of 1119; source: Cadence DE-HDL packaged netlist (pstxprt.dat, pstxnet.dat, pstchip.dat)

R319  RESISTOR  33OHM 1%  pkg SMC_0402R_H016  page 26 : 1 = FPGA_OUT_RGB_LED_SHUTDOWN_N ; 2 = RGB_LED_SHUTDOWN_N
R320  RESISTOR  4.7KOHM 1%  pkg SMC_0402R_H016  page 26 : 1 = XP3R3V_FPGA ; 2 = RGB_LED_SHUTDOWN_N
R321  RESISTOR  33OHM 1%  pkg SMC_0402R_H016  page 26 : 1 = FPGA_M_RGB_LED_I2C_SDA ; 2 = R_RGB_LED_I2C_SDA
R322  RESISTOR  33OHM 1%  pkg SMC_0402R_H016  page 26 : 1 = FPGA_M_RGB_LED_I2C_SCL ; 2 = R_RGB_LED_I2C_SCL
R323  RESISTOR  4.7KOHM 1%  pkg SMC_0402R_H016  page 26 : 1 = UNNAMED_14_IS32FL3207QWLA3TRQ_1 ; 2 = SG
R324  RESISTOR  0OHM -  pkg SMC_0402R_H016  page 26 : 1 = SG ; 2 = UNNAMED_14_IS32FL3207QWLA3TRQFN
R325  RESISTOR  10KOHM 1%  pkg SMC_0402R_H016  page 25 : 1 = XP3R3V_FPGA ; 2 = FPGA_IO_6
R326  RESISTOR  4.7KOHM 1%  pkg SMC_0402R_H016  page 25 : 1 = SG ; 2 = FPGA_IO_6
R327  RESISTOR  10KOHM 1%  pkg SMC_0402R_H016  page 25 : 1 = XP3R3V_FPGA ; 2 = FPGA_IO_7
R328  RESISTOR  4.7KOHM 1%  pkg SMC_0402R_H016  page 25 : 1 = SG ; 2 = FPGA_IO_7
R329  RESISTOR  33OHM 1%  pkg SMC_0402R_H016  page 25 : 1 = FPGA_IO_7 ; 2 = UNNAMED_16_CONNHDR2X6FSSMT_I1_4
R330  RESISTOR  33OHM 1%  pkg SMC_0402R_H016  page 20 : 1 = R_BNO080_EVN_SDA ; 2 = BNO080_EVN_SDA
R331  RESISTOR  4.7KOHM 1%  pkg SMC_0402R_H016  page 23 : 1 = XP3R3V_FPGA ; 2 = SMA2_SIG_OUT_BF_EN_N
R332  RESISTOR  33OHM 1%  pkg SMC_0402R_H016  page 17 : 1 = LM75B_I2C_SDA ; 2 = R_LM75B_1_I2C_SDA
R333  RESISTOR  4.7KOHM 1%  pkg SMC_0402R_H016  page 17 : 1 = XP3R3V_FPGA ; 2 = UNNAMED_6_LM75BDPTSSOP8_I34_A2
R334  RESISTOR  1KOHM 1%  pkg SMC_0402R_H016  page 17 : 1 = UNNAMED_6_LM75BDPTSSOP8_I34_A2 ; 2 = SG
R335  RESISTOR  4.7KOHM 1%  pkg SMC_0402R_H016  page 17 : 1 = XP3R3V_FPGA ; 2 = UNNAMED_6_LM75BDPTSSOP8_I34_A1
R336  RESISTOR  1KOHM 1%  pkg SMC_0402R_H016  page 17 : 1 = UNNAMED_6_LM75BDPTSSOP8_I34_A1 ; 2 = SG
R337  RESISTOR  4.7KOHM 1%  pkg SMC_0402R_H016  page 17 : 1 = XP3R3V_FPGA ; 2 = UNNAMED_6_LM75BDPTSSOP8_I34_A0
R338  RESISTOR  1KOHM 1%  pkg SMC_0402R_H016  page 17 : 1 = UNNAMED_6_LM75BDPTSSOP8_I34_A0 ; 2 = SG
R339  RESISTOR  33OHM 1%  pkg SMC_0402R_H016  page 11 : 1 = FPGA_D02 ; 2 = FPGA_FLASH_DQ2
R340  RESISTOR  4.7KOHM 1%  pkg SMC_0402R_H016  page 17 : 1 = XP3R3V_FPGA ; 2 = FPGA_IN_LM75B_INT1_N
R341  RESISTOR  4.7KOHM 1%  pkg SMC_0402R_H016  page 20 : 1 = XP3R3V_FPGA ; 2 = BNO080_EVN_SDA
R342  RESISTOR  4.7KOHM 1%  pkg SMC_0402R_H016  page 20 : 1 = XP3R3V_FPGA ; 2 = BNO080_EVN_SCL
R343  RESISTOR  0OHM -  pkg SMC_0402R_H016  page 19 : 1 = UNNAMED_8_ICP10100LGA10_I24_RES ; 2 = SG
R344  RESISTOR  4.7KOHM 1%  pkg SMC_0402R_H016  page 16 : 1 = SN_EEPROM_WP ; 2 = SG
R345  RESISTOR  33OHM 1%  pkg SMC_0402R_H016  page 16 : 1 = EEPROM_SDA ; 2 = PRI_EEPROM_SDA
R346  RESISTOR  0OHM -  pkg SMC_0402R_H016  page 19 : 1 = UNNAMED_8_ICP10100LGA10_I24_R_1 ; 2 = SG
R347  RESISTOR  0OHM -  pkg SMC_0402R_H016  page 19 : 1 = UNNAMED_8_ICP10100LGA10_I24_R_2 ; 2 = XP1R8V_ICP10100
R348  RESISTOR  33OHM 1%  pkg SMC_0402R_H016  page 11 : 1 = FPGA_D03 ; 2 = FPGA_FLASH_DQ3
R349  RESISTOR  100KOHM 1%  pkg SMC_0402R_H016  page 24 : 1 = R_FT4232_CHD_RX ; 2 = XP3R3V_FT4232
R350  RESISTOR  0OHM -  pkg SMC_0402R_H016  page 19 : 1 = UNNAMED_8_ICP10100LGA10_I24_R_3 ; 2 = XP1R8V_ICP10100
R351  RESISTOR  0OHM -  pkg SMC_0402R_H016  page 19 : 1 = UNNAMED_8_ICP10100LGA10_I24_R_4 ; 2 = SG
R352  RESISTOR  100OHM 1%  pkg SMC_0402R_H016  page 24 : 1 = R_FT4232_CHC_RX ; 2 = UART_FT4232_RX_FPGA_TX
R353  RESISTOR  100OHM 1%  pkg SMC_0402R_H016  page 24 : 1 = R_FT4232_CHC_TX ; 2 = UART_FT4232_TX_FPGA_RX
R354  RESISTOR  33OHM 1%  pkg SMC_0402R_H016  page 9 : 1 = FPGA_OUT_I2C_BUFFER_EN ; 2 = UNNAMED_3_G2201019801_I100_EN
R355  RESISTOR  10KOHM 1%  pkg SMC_0402R_H016  page 13 : 1 = MHZ200CLKN_CLKIN ; 2 = XP2R5V_FPGA
R356  RESISTOR  0OHM -  pkg SMC_0402R_H016  page 9 : 1 = BF_PCIE_PERST_N ; 2 = FPGA_PROGRAM_N
R357  RESISTOR  0OHM -  pkg SMC_0805R_H026  page 21 : 1 = XP5R0V_MAC ; 2 = UNNAMED_527_FUSE_I244_1
R358  RESISTOR  10KOHM 1%  pkg SMC_0402R_H016  page 13 : 1 = MHZ200CLKP_CLKIN ; 2 = XP2R5V_FPGA
R359  RESISTOR  10KOHM 1%  pkg SMC_0402R_H016  page 13 : 1 = MHZ200CLKP_CLKIN ; 2 = SG
R360  RESISTOR  10KOHM 1%  pkg SMC_0402R_H016  page 13 : 1 = MHZ200CLKN_CLKIN ; 2 = SG
R361  RESISTOR  4.7KOHM 1%  pkg SMC_0402R_H016  page 23 : 1 = XP3R3V_FPGA ; 2 = SMA1_SIG_OUT_BF_EN_N
R362  RESISTOR  33OHM 1%  pkg SMC_0402R_H016  page 11 : 1 = FPGA_FCS_B ; 2 = FPGA_FLASH_CS_N
R363  RESISTOR  33OHM 1%  pkg SMC_0402R_H016  page 20 : 1 = R_BNO080_EVN_SCL ; 2 = BNO080_EVN_SCL
R364  RESISTOR  33OHM 1%  pkg SMC_0402R_H016  page 26 : 1 = RGB_LED_I2C_SDA ; 2 = R_RGB_LED_I2C_SDA
R365  RESISTOR  4.7KOHM 1%  pkg SMC_0402R_H016  page 23 : 1 = XP3R3V_FPGA ; 2 = SMA3_SIG_OUT_BF_EN_N
R366  RESISTOR  33OHM 1%  pkg SMC_0402R_H016  page 26 : 1 = RGB_LED_I2C_SCL ; 2 = R_RGB_LED_I2C_SCL
R367  RESISTOR  49.9OHM 1%  pkg SMC_0402R_H016  page 23 : 1 = BF_ANT3_IN ; 2 = ANT3_IN
R368  RESISTOR  4.7KOHM 1%  pkg SMC_0402R_H016  page 23 : 1 = XP3R3V_FPGA ; 2 = SMA4_SIG_OUT_BF_EN_N
R370  RESISTOR  49.9OHM 1%  pkg SMC_0402R_H016  page 23 : 1 = BF_ANT4_IN ; 2 = ANT4_IN
R371  RESISTOR  49.9OHM 1%  pkg SMC_0402R_H016  page 23 : 1 = BF_ANT1_IN ; 2 = ANT1_IN
R372  RESISTOR  49.9OHM 1%  pkg SMC_0402R_H016  page 23 : 1 = BF_ANT2_IN ; 2 = ANT2_IN
R373  RESISTOR  100OHM 1%  pkg SMC_0402R_H016  page 26 : 1 = FPGA_OUT_SMA2_LED_RED_N ; 2 = UNNAMED_14_LED4PV14_I266_3
R374  RESISTOR  100OHM 1%  pkg SMC_0402R_H016  page 26 : 1 = FPGA_OUT_SMA3_LED_BLUE_N ; 2 = UNNAMED_14_LED4PV14_I267_1
R375  RESISTOR  100OHM 1%  pkg SMC_0402R_H016  page 26 : 1 = FPGA_OUT_SMA3_LED_GREEN_N ; 2 = UNNAMED_14_LED4PV14_I267_4
R376  RESISTOR  100OHM 1%  pkg SMC_0402R_H016  page 26 : 1 = FPGA_OUT_SMA3_LED_RED_N ; 2 = UNNAMED_14_LED4PV14_I267_3
R377  RESISTOR  4.7KOHM 1%  pkg SMC_0402R_H016  page 23 : 1 = XP3R3V_FPGA ; 2 = SMA3_SIG_IN_BF_EN_N
R379  RESISTOR  4.7KOHM 1%  pkg SMC_0402R_H016  page 23 : 1 = XP3R3V_FPGA ; 2 = SMA4_SIG_IN_BF_EN_N
R381  RESISTOR  4.7KOHM 1%  pkg SMC_0402R_H016  page 23 : 1 = XP3R3V_FPGA ; 2 = SMA1_SIG_IN_BF_EN_N
R383  RESISTOR  4.7KOHM 1%  pkg SMC_0402R_H016  page 23 : 1 = XP3R3V_FPGA ; 2 = SMA2_SIG_IN_BF_EN_N
R385  RESISTOR  33OHM 1%  pkg SMC_0402R_H016  page 26 : 1 = SMA1_LED_BLUE_N ; 2 = UNNAMED_14_LED4PV14_I265_1
R386  RESISTOR  33OHM 1%  pkg SMC_0402R_H016  page 26 : 1 = SMA1_LED_GREEN_N ; 2 = UNNAMED_14_LED4PV14_I265_4
R387  RESISTOR  33OHM 1%  pkg SMC_0402R_H016  page 26 : 1 = SMA1_LED_RED_N ; 2 = UNNAMED_14_LED4PV14_I265_3
R388  RESISTOR  33OHM 1%  pkg SMC_0402R_H016  page 26 : 1 = SMA2_LED_BLUE_N ; 2 = UNNAMED_14_LED4PV14_I266_1
R389  RESISTOR  33OHM 1%  pkg SMC_0402R_H016  page 26 : 1 = SMA2_LED_GREEN_N ; 2 = UNNAMED_14_LED4PV14_I266_4
R390  RESISTOR  33OHM 1%  pkg SMC_0402R_H016  page 26 : 1 = SMA2_LED_RED_N ; 2 = UNNAMED_14_LED4PV14_I266_3
R391  RESISTOR  33OHM 1%  pkg SMC_0402R_H016  page 26 : 1 = SMA3_LED_BLUE_N ; 2 = UNNAMED_14_LED4PV14_I267_1
R392  RESISTOR  33OHM 1%  pkg SMC_0402R_H016  page 26 : 1 = SMA3_LED_GREEN_N ; 2 = UNNAMED_14_LED4PV14_I267_4
R393  RESISTOR  33OHM 1%  pkg SMC_0402R_H016  page 26 : 1 = SMA3_LED_RED_N ; 2 = UNNAMED_14_LED4PV14_I267_3
R394  RESISTOR  33OHM 1%  pkg SMC_0402R_H016  page 26 : 1 = SMA4_LED_BLUE_N ; 2 = UNNAMED_14_LED4PV14_I268_1
R395  RESISTOR  33OHM 1%  pkg SMC_0402R_H016  page 26 : 1 = SMA4_LED_GREEN_N ; 2 = UNNAMED_14_LED4PV14_I268_4
R396  RESISTOR  33OHM 1%  pkg SMC_0402R_H016  page 26 : 1 = SMA4_LED_RED_N ; 2 = UNNAMED_14_LED4PV14_I268_3
R397  RESISTOR  33OHM 1%  pkg SMC_0402R_H016  page 26 : 1 = GPS_SMA_LED_BLUE_N ; 2 = UNNAMED_14_LED4PV14_I269_1
R398  RESISTOR  33OHM 1%  pkg SMC_0402R_H016  page 26 : 1 = GPS_SMA_LED_GREEN_N ; 2 = UNNAMED_14_LED4PV14_I269_4
R399  RESISTOR  33OHM 1%  pkg SMC_0402R_H016  page 26 : 1 = GPS_SMA_LED_RED_N ; 2 = UNNAMED_14_LED4PV14_I269_3
R400  RESISTOR  100OHM 1%  pkg SMC_0402R_H016  page 26 : 1 = FPGA_OUT_SMA4_LED_BLUE_N ; 2 = UNNAMED_14_LED4PV14_I268_1
R401  RESISTOR  100OHM 1%  pkg SMC_0402R_H016  page 26 : 1 = FPGA_OUT_SMA4_LED_GREEN_N ; 2 = UNNAMED_14_LED4PV14_I268_4
R402  RESISTOR  2.2KOHM 1%  pkg SMC_0402R_H016  page 10 : 1 = FPGA_TCK ; 2 = SG
R403  RESISTOR  10KOHM 1%  pkg SMC_0402R_H016  page 10 : 1 = XP3R3V_FPGA ; 2 = FPGA_TDO
R404  RESISTOR  10KOHM 1%  pkg SMC_0402R_H016  page 10 : 1 = XP3R3V_FPGA ; 2 = FPGA_TMS
R405  RESISTOR  10KOHM 1%  pkg SMC_0402R_H016  page 10 : 1 = XP3R3V_FPGA ; 2 = FPGA_TDI
R406  RESISTOR  33OHM 1%  pkg SMC_0402R_H016  page 17 : 1 = LM75B_I2C_SDA ; 2 = R_LM75B_2_I2C_SDA
R407  RESISTOR  33OHM 1%  pkg SMC_0402R_H016  page 17 : 1 = LM75B_I2C_SDA ; 2 = R_LM75B_3_I2C_SDA
R408  RESISTOR  4.7KOHM 1%  pkg SMC_0402R_H016  page 17 : 1 = XP3R3V_FPGA ; 2 = UNNAMED_6_LM75BDPTSSOP8_I59_A2
R409  RESISTOR  1KOHM 1%  pkg SMC_0402R_H016  page 17 : 1 = UNNAMED_6_LM75BDPTSSOP8_I59_A2 ; 2 = SG
R410  RESISTOR  4.7KOHM 1%  pkg SMC_0402R_H016  page 17 : 1 = XP3R3V_FPGA ; 2 = UNNAMED_6_LM75BDPTSSOP8_I81_A2
R411  RESISTOR  1KOHM 1%  pkg SMC_0402R_H016  page 17 : 1 = UNNAMED_6_LM75BDPTSSOP8_I81_A2 ; 2 = SG
R412  RESISTOR  4.7KOHM 1%  pkg SMC_0402R_H016  page 17 : 1 = XP3R3V_FPGA ; 2 = UNNAMED_6_LM75BDPTSSOP8_I59_A1
R413  RESISTOR  1KOHM 1%  pkg SMC_0402R_H016  page 17 : 1 = UNNAMED_6_LM75BDPTSSOP8_I59_A1 ; 2 = SG
R414  RESISTOR  4.7KOHM 1%  pkg SMC_0402R_H016  page 17 : 1 = XP3R3V_FPGA ; 2 = UNNAMED_6_LM75BDPTSSOP8_I81_A1
R415  RESISTOR  1KOHM 1%  pkg SMC_0402R_H016  page 17 : 1 = UNNAMED_6_LM75BDPTSSOP8_I81_A1 ; 2 = SG
R416  RESISTOR  1KOHM 1%  pkg SMC_0402R_H016  page 17 : 1 = UNNAMED_6_LM75BDPTSSOP8_I59_A0 ; 2 = SG
R417  RESISTOR  1KOHM 1%  pkg SMC_0402R_H016  page 17 : 1 = UNNAMED_6_LM75BDPTSSOP8_I81_A0 ; 2 = SG
R418  RESISTOR  4.7KOHM 1%  pkg SMC_0402R_H016  page 17 : 1 = XP3R3V_FPGA ; 2 = UNNAMED_6_LM75BDPTSSOP8_I59_A0
R419  RESISTOR  4.7KOHM 1%  pkg SMC_0402R_H016  page 17 : 1 = XP3R3V_FPGA ; 2 = UNNAMED_6_LM75BDPTSSOP8_I81_A0
R422  RESISTOR  4.7KOHM 1%  pkg SMC_0402R_H016  page 17 : 1 = XP3R3V_FPGA ; 2 = FPGA_IN_LM75B_INT2_N
R423  RESISTOR  4.7KOHM 1%  pkg SMC_0402R_H016  page 17 : 1 = XP3R3V_FPGA ; 2 = FPGA_IN_LM75B_INT3_N
R424  RESISTOR  100OHM 1%  pkg SMC_0402R_H016  page 26 : 1 = FPGA_OUT_SMA4_LED_RED_N ; 2 = UNNAMED_14_LED4PV14_I268_3
R425  RESISTOR  100OHM 1%  pkg SMC_0402R_H016  page 26 : 1 = FPGA_OUT_GPS_LED_BLUE_N ; 2 = UNNAMED_14_LED4PV14_I269_1
R426  RESISTOR  100OHM 1%  pkg SMC_0402R_H016  page 26 : 1 = FPGA_OUT_GPS_LED_GREEN_N ; 2 = UNNAMED_14_LED4PV14_I269_4
R427  RESISTOR  100OHM 1%  pkg SMC_0402R_H016  page 26 : 1 = FPGA_OUT_GPS_LED_RED_N ; 2 = UNNAMED_14_LED4PV14_I269_3
R428  RESISTOR  33OHM 1%  pkg SMC_0402R_H016  page 25 : 1 = FPGA_IO_6 ; 2 = UNNAMED_16_CONNHDR2X6FSSMT_I1_6
R429  RESISTOR  33OHM 1%  pkg SMC_0402R_H016  page 25 : 1 = FPGA_IO_5 ; 2 = UNNAMED_16_CONNHDR2X6FSSMT_I1_2
R430  RESISTOR  33OHM 1%  pkg SMC_0402R_H016  page 25 : 1 = FPGA_IO_4 ; 2 = UNNAMED_16_CONNHDR2X6FSSMT_I161
R431  RESISTOR  33OHM 1%  pkg SMC_0402R_H016  page 25 : 1 = UNNAMED_16_CONNHDR2X6FSSMT_I1_5 ; 2 = FPGA_IO_3
R432  RESISTOR  33OHM 1%  pkg SMC_0402R_H016  page 25 : 1 = UNNAMED_16_CONNHDR2X6FSSMT_I1_7 ; 2 = FPGA_IO_2
R433  RESISTOR  33OHM 1%  pkg SMC_0402R_H016  page 25 : 1 = UNNAMED_16_CONNHDR2X6FSSMT_I1_3 ; 2 = FPGA_IO_1
R434  RESISTOR  33OHM 1%  pkg SMC_0402R_H016  page 25 : 1 = UNNAMED_16_CONNHDR2X6FSSMT_I1_1 ; 2 = FPGA_IO_0
R435  RESISTOR  100KOHM 1%  pkg SMC_0402R_H016  page 11 : 1 = FPGA_FLASH_DQ1_MISO ; 2 = XP3R3V_FPGA
R436  RESISTOR  15KOHM 1%  pkg SMC_0402R_H016  page 11 : 1 = SG ; 2 = MAC_USB_DP
R437  RESISTOR  15KOHM 1%  pkg SMC_0402R_H016  page 11 : 1 = SG ; 2 = MAC_USB_DM
R438  RESISTOR  10KOHM 1%  pkg SMC_0402R_H016  page 13 : 1 = FPGA_IN_MAC_PPS_OUTN ; 2 = XP2R5V_FPGA
R439  RESISTOR  10KOHM 1%  pkg SMC_0402R_H016  page 13 : 1 = FPGA_IN_MAC_PPS_OUTP ; 2 = XP2R5V_FPGA
R440  RESISTOR  10KOHM 1%  pkg SMC_0402R_H016  page 13 : 1 = FPGA_IN_MAC_PPS_OUTP ; 2 = SG
R441  RESISTOR  10KOHM 1%  pkg SMC_0402R_H016  page 13 : 1 = FPGA_IN_MAC_PPS_OUTN ; 2 = SG
R442  RESISTOR  5.1KOHM 1%  pkg SMC_0402R_H016  page 24 : 1 = UNNAMED_524_CONNUSB14PGH4FRATH_ ; 2 = SG
R443  RESISTOR  100OHM 1%  pkg SMC_0402R_H016  page 24 : 1 = FT_USB_DETECT ; 2 = FPGA_IO_FT_USBDET_RST_N
R444  RESISTOR  10KOHM 1%  pkg SMC_0402R_H016  page 24 : 1 = XP3R3V_FT4232 ; 2 = FTDI_EE_DO
R445  RESISTOR  5.1KOHM 1%  pkg SMC_0402R_H016  page 24 : 1 = UNNAMED_524_CONNUSB14PGH4FRAT_1 ; 2 = SG
R446  RESISTOR  10KOHM 1%  pkg SMC_0402R_H016  page 24 : 1 = XP3R3V_FT4232 ; 2 = FTDI_EE_CS
R447  RESISTOR  10KOHM 1%  pkg SMC_0402R_H016  page 24 : 1 = XP3R3V_FT4232 ; 2 = FTDI_EE_CLK
R448  RESISTOR  33OHM 1%  pkg SMC_0402R_H016  page 24 : 1 = MUX1_SEL ; 2 = FPGA_OUT_MUX1_SEL
R449  RESISTOR  33OHM 1%  pkg SMC_0402R_H016  page 24 : 1 = MUX1_SEL ; 2 = FT4232_MUX1_SEL
R450  RESISTOR  4.7KOHM 1%  pkg SMC_0402R_H016  page 24 : 1 = MUX1_SEL ; 2 = XP3R3V_FPGA
R451  RESISTOR  1KOHM 1%  pkg SMC_0402R_H016  page 24 : 1 = MUX1_SEL ; 2 = SG
R452  RESISTOR  4.7KOHM 1%  pkg SMC_0402R_H016  page 24 : 1 = UNNAMED_524_POWERMOS3PNCHV1_I44 ; 2 = XP3R3V_FPGA
R453  RESISTOR  1KOHM 1%  pkg SMC_0402R_H016  page 24 : 1 = UNNAMED_524_POWERMOS3PNCHV1_I44 ; 2 = SG
R454  RESISTOR  2.2KOHM 1%  pkg SMC_0402R_H016  page 24 : 1 = FTDI_EE_DAT ; 2 = FTDI_EE_DO
R455  RESISTOR  1MOHM 1%  pkg SMC_0402R_H016  page 24 : 1 = UNNAMED_524_CAPACITOR_I7_2 ; 2 = UNNAMED_524_CAPACITOR_I10_2
R456  RESISTOR  100OHM 1%  pkg SMC_0402R_H016  page 24 : 1 = XP3R3V_FT_PG ; 2 = FT_USB_DETECT
R457  RESISTOR  4.7KOHM 1%  pkg SMC_0402R_H016  page 24 : 1 = XP3R3V_FPGA ; 2 = MUX2_SEL
R458  RESISTOR  1KOHM 1%  pkg SMC_0402R_H016  page 24 : 1 = SG ; 2 = MUX2_SEL
R459  RESISTOR  1KOHM 1%  pkg SMC_0402R_H016  page 24 : 1 = SG ; 2 = UNNAMED_524_RESISTOR_I432_2
R460  RESISTOR  1KOHM 1%  pkg SMC_0402R_H016  page 24 : 1 = FT_USB_DETECT ; 2 = UNNAMED_524_FT4232HLREELQFP64_7
R461  RESISTOR  33OHM 1%  pkg SMC_0402R_H016  page 24 : 1 = FPGA_OUT_MUX2_SEL ; 2 = MUX2_SEL
R462  RESISTOR  33OHM 1%  pkg SMC_0402R_H016  page 24 : 1 = FT4232_MUX2_SEL ; 2 = MUX2_SEL
R463  RESISTOR  12KOHM 1%  pkg SMC_0402R  page 24 : 1 = UNNAMED_524_FT4232HLREELQFP64_6 ; 2 = SG
R464  RESISTOR  0OHM -  pkg SMC_0402R_H016  page 24 : 1 = FPGA_FLASH_DQ2 ; 2 = FLASH_DQ2
R465  RESISTOR  0OHM -  pkg SMC_0402R_H016  page 24 : 1 = FPGA_FLASH_DQ3 ; 2 = FLASH_DQ3
R466  RESISTOR  100KOHM 1%  pkg SMC_0402R_H016  page 24 : 1 = R_FT4232_TDO ; 2 = XP3R3V_FT4232
R467  RESISTOR  33OHM 1%  pkg SMC_0402R_H016  page 24 : 1 = R_FT4232_TCK ; 2 = FT4232_TCK_SCLK
R468  RESISTOR  33OHM 1%  pkg SMC_0402R_H016  page 24 : 1 = R_FT4232_TDI ; 2 = FT4232_TDI_MOSI
R469  RESISTOR  33OHM 1%  pkg SMC_0402R_H016  page 24 : 1 = R_FT4232_TDO ; 2 = FT4232_TDO_MISO
R470  RESISTOR  33OHM 1%  pkg SMC_0402R_H016  page 24 : 1 = R_FT4232_TMS ; 2 = FT4232_TMS_SPICS_N
R471  RESISTOR  0OHM -  pkg SMC_0402R_H016  page 24 : 1 = R_FT4232_I2C_SCL ; 2 = FT4232_I2C_SCL
